(kicad_pcb
	(version 20221018)
	(generator pcbnew)
	(general
    (thickness 1.518)
  )
	(paper "A4")
	(title_block
    (title "Kria K26 Devboard")
    (date "2024-03-26")
    (rev "1.2.5")
    (comment 1 "www.antmicro.com")
    (comment 2 "Antmicro Ltd.")
		(comment 9 "footprints 499-507 of 660")
	)
	(layers
    (0 "F.Cu" mixed)
    (1 "In1.Cu" power)
    (2 "In2.Cu" mixed)
    (3 "In3.Cu" power)
    (4 "In4.Cu" mixed)
    (5 "In5.Cu" power)
    (6 "In6.Cu" mixed)
    (31 "B.Cu" power)
    (32 "B.Adhes" user "B.Adhesive")
    (33 "F.Adhes" user "F.Adhesive")
    (34 "B.Paste" user)
    (35 "F.Paste" user)
    (36 "B.SilkS" user "B.Silkscreen")
    (37 "F.SilkS" user "F.Silkscreen")
    (38 "B.Mask" user)
    (39 "F.Mask" user)
    (40 "Dwgs.User" user "User.Drawings")
    (41 "Cmts.User" user "User.Comments")
    (42 "Eco1.User" user "User.Eco1")
    (43 "Eco2.User" user "User.Eco2")
    (44 "Edge.Cuts" user)
    (45 "Margin" user)
    (46 "B.CrtYd" user "B.Courtyard")
    (47 "F.CrtYd" user "F.Courtyard")
    (48 "B.Fab" user)
    (49 "F.Fab" user)
  )
	(footprint "kria-k26-devboard-footprints:C_0402_1005Metric" (layer "B.Cu")
    (at 145.83 114.935 -90)
    (descr "Capacitor SMD 0402")
    (tags "capacitor SMD 0402")
    (property "Author" "Antmicro")
    (property "Dielectric" "X5R")
    (property "License" "Apache-2.0")
    (property "MPN" "GRM155R61H104KE14D")
    (property "Manufacturer" "Murata")
    (property "Sheetfile" "debug.kicad_sch")
    (property "Sheetname" "Debug and JTAG")
    (property "Val" "100n")
    (property "Voltage" "50V")
    (property "ki_description" " ")
    (attr smd)
    (fp_text reference "C147" (at -1.455 1.46 90) (layer "B.SilkS")
        (effects (font (size 0.7 0.7) (thickness 0.15)) (justify left bottom mirror))
    )
    (fp_text value "C_100n_0402" (at 0 -1.4 90) (layer "B.Fab") hide
        (effects (font (size 0.7 0.7) (thickness 0.15)) (justify left bottom mirror))
    )
    (fp_text user "License: Apache-2.0" (at -0.932 -5.17 90) (layer "B.Fab") hide
        (effects (font (size 0.7 0.7) (thickness 0.15)) (justify left bottom mirror))
    )
    (fp_text user "${REFERENCE}" (at -0.932 -3.168 90) (layer "B.Fab") hide
        (effects (font (size 0.7 0.7) (thickness 0.15)) (justify left bottom mirror))
    )
    (fp_text user "Author: Antmicro" (at -0.932 -4.17 90) (layer "B.Fab") hide
        (effects (font (size 0.7 0.7) (thickness 0.15)) (justify left bottom mirror))
    )
    (fp_rect (start -0.94 0.47) (end 0.94 -0.47)
      (stroke (width 0.05) (type solid)) (fill none) (layer "B.CrtYd"))
    (fp_rect (start -0.499 0.249) (end 0.499 -0.249)
      (stroke (width 0.15) (type solid)) (fill none) (layer "B.Fab"))
    (pad "1" smd roundrect (at -0.484 0 270) (size 0.59 0.64) (layers "B.Cu" "B.Paste" "B.Mask") (roundrect_rratio 0.25)
      (net 132 "/Debug and JTAG/USB_1V2") (pintype "passive"))
    (pad "2" smd roundrect (at 0.484 0 270) (size 0.59 0.64) (layers "B.Cu" "B.Paste" "B.Mask") (roundrect_rratio 0.25)
      (net 1 "GND") (pintype "passive"))
  )
	(footprint "kria-k26-devboard-footprints:C_0402_1005Metric" (layer "B.Cu")
    (at 146.78 114.935 -90)
    (descr "Capacitor SMD 0402")
    (tags "capacitor SMD 0402")
    (property "Author" "Antmicro")
    (property "Dielectric" "X5R")
    (property "License" "Apache-2.0")
    (property "MPN" "GRM155R61H104KE14D")
    (property "Manufacturer" "Murata")
    (property "Sheetfile" "debug.kicad_sch")
    (property "Sheetname" "Debug and JTAG")
    (property "Val" "100n")
    (property "Voltage" "50V")
    (property "ki_description" " ")
    (attr smd)
    (fp_text reference "C148" (at -1.455 1.46 90) (layer "B.SilkS")
        (effects (font (size 0.7 0.7) (thickness 0.15)) (justify left bottom mirror))
    )
    (fp_text value "C_100n_0402" (at 0 -1.4 90) (layer "B.Fab") hide
        (effects (font (size 0.7 0.7) (thickness 0.15)) (justify left bottom mirror))
    )
    (fp_text user "Author: Antmicro" (at -0.932 -4.17 90) (layer "B.Fab") hide
        (effects (font (size 0.7 0.7) (thickness 0.15)) (justify left bottom mirror))
    )
    (fp_text user "${REFERENCE}" (at -0.932 -3.168 90) (layer "B.Fab") hide
        (effects (font (size 0.7 0.7) (thickness 0.15)) (justify left bottom mirror))
    )
    (fp_text user "License: Apache-2.0" (at -0.932 -5.17 90) (layer "B.Fab") hide
        (effects (font (size 0.7 0.7) (thickness 0.15)) (justify left bottom mirror))
    )
    (fp_rect (start -0.94 0.47) (end 0.94 -0.47)
      (stroke (width 0.05) (type solid)) (fill none) (layer "B.CrtYd"))
    (fp_rect (start -0.499 0.249) (end 0.499 -0.249)
      (stroke (width 0.15) (type solid)) (fill none) (layer "B.Fab"))
    (pad "1" smd roundrect (at -0.484 0 270) (size 0.59 0.64) (layers "B.Cu" "B.Paste" "B.Mask") (roundrect_rratio 0.25)
      (net 133 "/Debug and JTAG/VCC_PD") (pintype "passive"))
    (pad "2" smd roundrect (at 0.484 0 270) (size 0.59 0.64) (layers "B.Cu" "B.Paste" "B.Mask") (roundrect_rratio 0.25)
      (net 1 "GND") (pintype "passive"))
  )
	(footprint "kria-k26-devboard-footprints:R_0402_1005Metric" (layer "B.Cu")
    (at 139.6 90.749999 90)
    (descr "Resistor SMD 0402")
    (tags "resistor SMD 0402")
    (property "Author" "Antmicro")
    (property "License" "Apache-2.0")
    (property "MPN" "CR0402-FX-2491GLF")
    (property "Manufacturer" "Bourns")
    (property "Sheetfile" "dc-dc-conventers.kicad_sch")
    (property "Sheetname" "DC/DC conventers")
    (property "Tolerance" "1%")
    (property "Val" "2k49")
    (property "ki_description" "2k49 resistor in 0402 package with 1% tolerance")
    (attr smd)
    (fp_text reference "R139" (at 1.379999 1.34 270) (layer "B.SilkS")
        (effects (font (size 0.7 0.7) (thickness 0.15)) (justify left bottom mirror))
    )
    (fp_text value "R_2k49_0402" (at 0 -1.4 270) (layer "B.Fab") hide
        (effects (font (size 0.7 0.7) (thickness 0.15)) (justify left bottom mirror))
    )
    (fp_text user "Author: Antmicro" (at -0.95 -4.169 270) (layer "B.Fab") hide
        (effects (font (size 0.7 0.7) (thickness 0.15)) (justify left bottom mirror))
    )
    (fp_text user "${REFERENCE}" (at -0.95 -3.168 270) (layer "B.Fab") hide
        (effects (font (size 0.7 0.7) (thickness 0.15)) (justify left bottom mirror))
    )
    (fp_text user "License: Apache-2.0" (at -0.95 -5.169 270) (layer "B.Fab") hide
        (effects (font (size 0.7 0.7) (thickness 0.15)) (justify left bottom mirror))
    )
    (fp_rect (start -0.93 0.47) (end 0.93 -0.47)
      (stroke (width 0.05) (type solid)) (fill none) (layer "B.CrtYd"))
    (fp_rect (start -0.5 0.25) (end 0.5 -0.25)
      (stroke (width 0.15) (type solid)) (fill none) (layer "B.Fab"))
    (pad "1" smd roundrect (at -0.485 0 90) (size 0.59 0.64) (layers "B.Cu" "B.Paste" "B.Mask") (roundrect_rratio 0.25)
      (net 769 "/Power Supply/DC/DC conventers/PS_1V0_OUT") (pintype "passive"))
    (pad "2" smd roundrect (at 0.485 0 90) (size 0.59 0.64) (layers "B.Cu" "B.Paste" "B.Mask") (roundrect_rratio 0.25)
      (net 692 "Net-(U53-FB)") (pintype "passive"))
  )
	(footprint "kria-k26-devboard-footprints:R_0402_1005Metric" (layer "B.Cu")
    (at 148.25 114.945 90)
    (descr "Resistor SMD 0402")
    (tags "resistor SMD 0402")
    (property "Author" "Antmicro")
    (property "License" "Apache-2.0")
    (property "MPN" "CR0402-FX-1202GLF")
    (property "Manufacturer" "Bourns")
    (property "Sheetfile" "debug.kicad_sch")
    (property "Sheetname" "Debug and JTAG")
    (property "Tolerance" "1%")
    (property "Val" "12k")
    (property "ki_description" "12k resistor in 0402 package with 1% tolerance")
    (attr smd)
    (fp_text reference "R102" (at -0.835 0.39 270) (layer "B.SilkS")
        (effects (font (size 0.7 0.7) (thickness 0.15)) (justify left bottom mirror))
    )
    (fp_text value "R_12k_0402" (at 0 -1.4 270) (layer "B.Fab") hide
        (effects (font (size 0.7 0.7) (thickness 0.15)) (justify left bottom mirror))
    )
    (fp_text user "${REFERENCE}" (at -0.95 -3.168 270) (layer "B.Fab") hide
        (effects (font (size 0.7 0.7) (thickness 0.15)) (justify left bottom mirror))
    )
    (fp_text user "License: Apache-2.0" (at -0.95 -5.169 270) (layer "B.Fab") hide
        (effects (font (size 0.7 0.7) (thickness 0.15)) (justify left bottom mirror))
    )
    (fp_text user "Author: Antmicro" (at -0.95 -4.169 270) (layer "B.Fab") hide
        (effects (font (size 0.7 0.7) (thickness 0.15)) (justify left bottom mirror))
    )
    (fp_rect (start -0.93 0.47) (end 0.93 -0.47)
      (stroke (width 0.05) (type solid)) (fill none) (layer "B.CrtYd"))
    (fp_rect (start -0.5 0.25) (end 0.5 -0.25)
      (stroke (width 0.15) (type solid)) (fill none) (layer "B.Fab"))
    (pad "1" smd roundrect (at -0.485 0 90) (size 0.59 0.64) (layers "B.Cu" "B.Paste" "B.Mask") (roundrect_rratio 0.25)
      (net 1 "GND") (pintype "passive"))
    (pad "2" smd roundrect (at 0.485 0 90) (size 0.59 0.64) (layers "B.Cu" "B.Paste" "B.Mask") (roundrect_rratio 0.25)
      (net 680 "Net-(U40-REF)") (pintype "passive"))
  )
	(footprint "kria-k26-devboard-footprints:TSOT23-6" (layer "B.Cu")
    (at 137.05 91.25 90)
    (property "Author" "Antmicro")
    (property "License" "Apache-2.0")
    (property "MPN" "AP62301WU-7")
    (property "Manufacturer" "Diodes Incorporated")
    (property "Sheetfile" "dc-dc-conventers.kicad_sch")
    (property "Sheetname" "DC/DC conventers")
    (property "ki_description" "DC-DC Switching Synchronous Buck Regulator, Adjustable, 4.2V-18Vin, 0.8V-7V/3A out, TSOT-26-6")
    (property "ki_keywords" "SMT, PMIC, IC, VOLTAGE")
    (attr smd)
    (fp_text reference "U53" (at 1.78 0.62) (layer "B.SilkS")
        (effects (font (size 0.7 0.7) (thickness 0.15)) (justify left bottom mirror))
    )
    (fp_text value "AP62301_TSOT" (at -0.005 -2.6 270) (layer "B.Fab") hide
        (effects (font (size 0.7 0.7) (thickness 0.15)) (justify left bottom mirror))
    )
    (fp_text user "Author: Antmicro" (at -1.893 -7.368 270) (layer "B.Fab") hide
        (effects (font (size 0.7 0.7) (thickness 0.15)) (justify left bottom mirror))
    )
    (fp_text user "${REFERENCE}" (at -1.893 -6.168 270) (layer "B.Fab") hide
        (effects (font (size 0.7 0.7) (thickness 0.15)) (justify left bottom mirror))
    )
    (fp_text user "License: Apache-2.0" (at -1.893 -4.967 270) (layer "B.Fab") hide
        (effects (font (size 0.7 0.7) (thickness 0.15)) (justify left bottom mirror))
    )
    (fp_line (start -1.4805 -0.725) (end -1.4795 0.725)
      (stroke (width 0.15) (type solid)) (layer "B.SilkS"))
    (fp_line (start -1.4805 -0.725) (end -1.3905 -0.725)
      (stroke (width 0.15) (type solid)) (layer "B.SilkS"))
    (fp_line (start -1.4795 0.725) (end -1.3905 0.725)
      (stroke (width 0.15) (type solid)) (layer "B.SilkS"))
    (fp_line (start 1.479 -0.73) (end 1.38 -0.73)
      (stroke (width 0.15) (type solid)) (layer "B.SilkS"))
    (fp_line (start 1.48 0.72) (end 1.38 0.72)
      (stroke (width 0.15) (type solid)) (layer "B.SilkS"))
    (fp_line (start 1.48 0.72) (end 1.479 -0.73)
      (stroke (width 0.15) (type solid)) (layer "B.SilkS"))
    (fp_circle (center -1.499 -1.236) (end -1.45 -1.236)
      (stroke (width 0.15) (type solid)) (fill solid) (layer "B.SilkS"))
    (fp_rect (start -1.65 1.61) (end 1.65 -1.61)
      (stroke (width 0.05) (type solid)) (fill none) (layer "B.CrtYd"))
    (fp_line (start -1.527 -0.491) (end -1.527 0.833)
      (stroke (width 0.15) (type solid)) (layer "B.Fab"))
    (fp_line (start -1.527 -0.491) (end -1.102 -0.916)
      (stroke (width 0.15) (type solid)) (layer "B.Fab"))
    (fp_line (start -1.527 0.833) (end 1.523 0.833)
      (stroke (width 0.15) (type solid)) (layer "B.Fab"))
    (fp_line (start -1.102 -0.916) (end 1.523 -0.916)
      (stroke (width 0.15) (type solid)) (layer "B.Fab"))
    (fp_line (start 1.523 0.833) (end 1.523 -0.916)
      (stroke (width 0.15) (type solid)) (layer "B.Fab"))
    (pad "1" smd rect (at -0.952 -1.18 90) (size 0.7 0.8) (layers "B.Cu" "B.Paste" "B.Mask")
      (net 1 "GND") (pinfunction "GND") (pintype "power_in"))
    (pad "2" smd rect (at -0.001 -1.18 90) (size 0.7 0.8) (layers "B.Cu" "B.Paste" "B.Mask")
      (net 256 "/Power Supply/DC/DC conventers/SW_PS_1V0") (pinfunction "SW") (pintype "power_out"))
    (pad "3" smd rect (at 0.947 -1.18 90) (size 0.7 0.8) (layers "B.Cu" "B.Paste" "B.Mask")
      (net 14 "/Power Supply/DC/DC conventers/DC_MAIN_BUS") (pinfunction "VIN") (pintype "power_in"))
    (pad "4" smd rect (at 0.947 1.18 90) (size 0.7 0.8) (layers "B.Cu" "B.Paste" "B.Mask")
      (net 692 "Net-(U53-FB)") (pinfunction "FB") (pintype "input"))
    (pad "5" smd rect (at -0.001 1.18 90) (size 0.7 0.8) (layers "B.Cu" "B.Paste" "B.Mask")
      (net 687 "Net-(U50-EN)") (pinfunction "EN") (pintype "input"))
    (pad "6" smd rect (at -0.952 1.18 90) (size 0.7 0.8) (layers "B.Cu" "B.Paste" "B.Mask")
      (net 323 "Net-(U53-BST)") (pinfunction "BST") (pintype "output"))
  )
	(footprint "kria-k26-devboard-footprints:C_0402_1005Metric" (layer "B.Cu")
    (at 149.479999 114.945 -90)
    (descr "Capacitor SMD 0402")
    (tags "capacitor SMD 0402")
    (property "Author" "Antmicro")
    (property "Dielectric" "X5R")
    (property "License" "Apache-2.0")
    (property "MPN" "GRM155R61H104KE14D")
    (property "Manufacturer" "Murata")
    (property "Sheetfile" "debug.kicad_sch")
    (property "Sheetname" "Debug and JTAG")
    (property "Val" "100n")
    (property "Voltage" "50V")
    (property "ki_description" " ")
    (attr smd)
    (fp_text reference "C152" (at 0.865 -0.350001 90) (layer "B.SilkS")
        (effects (font (size 0.7 0.7) (thickness 0.15)) (justify left bottom mirror))
    )
    (fp_text value "C_100n_0402" (at 0 -1.4 90) (layer "B.Fab") hide
        (effects (font (size 0.7 0.7) (thickness 0.15)) (justify left bottom mirror))
    )
    (fp_text user "Author: Antmicro" (at -0.932 -4.17 90) (layer "B.Fab") hide
        (effects (font (size 0.7 0.7) (thickness 0.15)) (justify left bottom mirror))
    )
    (fp_text user "${REFERENCE}" (at -0.932 -3.168 90) (layer "B.Fab") hide
        (effects (font (size 0.7 0.7) (thickness 0.15)) (justify left bottom mirror))
    )
    (fp_text user "License: Apache-2.0" (at -0.932 -5.17 90) (layer "B.Fab") hide
        (effects (font (size 0.7 0.7) (thickness 0.15)) (justify left bottom mirror))
    )
    (fp_rect (start -0.94 0.47) (end 0.94 -0.47)
      (stroke (width 0.05) (type solid)) (fill none) (layer "B.CrtYd"))
    (fp_rect (start -0.499 0.249) (end 0.499 -0.249)
      (stroke (width 0.15) (type solid)) (fill none) (layer "B.Fab"))
    (pad "1" smd roundrect (at -0.484 0 270) (size 0.59 0.64) (layers "B.Cu" "B.Paste" "B.Mask") (roundrect_rratio 0.25)
      (net 135 "/Debug and JTAG/VCC_USB") (pintype "passive"))
    (pad "2" smd roundrect (at 0.484 0 270) (size 0.59 0.64) (layers "B.Cu" "B.Paste" "B.Mask") (roundrect_rratio 0.25)
      (net 1 "GND") (pintype "passive"))
  )
	(footprint "kria-k26-devboard-footprints:C_0402_1005Metric" (layer "B.Cu")
    (at 149.5 121.6 90)
    (descr "Capacitor SMD 0402")
    (tags "capacitor SMD 0402")
    (property "Author" "Antmicro")
    (property "Dielectric" "X5R")
    (property "License" "Apache-2.0")
    (property "MPN" "GRM155R61H104KE14D")
    (property "Manufacturer" "Murata")
    (property "Sheetfile" "debug.kicad_sch")
    (property "Sheetname" "Debug and JTAG")
    (property "Val" "100n")
    (property "Voltage" "50V")
    (property "ki_description" " ")
    (attr smd)
    (fp_text reference "C149" (at 1.26 4.35 270) (layer "B.SilkS")
        (effects (font (size 0.7 0.7) (thickness 0.15)) (justify left bottom mirror))
    )
    (fp_text value "C_100n_0402" (at 0 -1.4 270) (layer "B.Fab") hide
        (effects (font (size 0.7 0.7) (thickness 0.15)) (justify left bottom mirror))
    )
    (fp_text user "${REFERENCE}" (at -0.932 -3.168 270) (layer "B.Fab") hide
        (effects (font (size 0.7 0.7) (thickness 0.15)) (justify left bottom mirror))
    )
    (fp_text user "Author: Antmicro" (at -0.932 -4.17 270) (layer "B.Fab") hide
        (effects (font (size 0.7 0.7) (thickness 0.15)) (justify left bottom mirror))
    )
    (fp_text user "License: Apache-2.0" (at -0.932 -5.17 270) (layer "B.Fab") hide
        (effects (font (size 0.7 0.7) (thickness 0.15)) (justify left bottom mirror))
    )
    (fp_rect (start -0.94 0.47) (end 0.94 -0.47)
      (stroke (width 0.05) (type solid)) (fill none) (layer "B.CrtYd"))
    (fp_rect (start -0.499 0.249) (end 0.499 -0.249)
      (stroke (width 0.15) (type solid)) (fill none) (layer "B.Fab"))
    (pad "1" smd roundrect (at -0.484 0 90) (size 0.59 0.64) (layers "B.Cu" "B.Paste" "B.Mask") (roundrect_rratio 0.25)
      (net 134 "/Debug and JTAG/VREGIN") (pintype "passive"))
    (pad "2" smd roundrect (at 0.484 0 90) (size 0.59 0.64) (layers "B.Cu" "B.Paste" "B.Mask") (roundrect_rratio 0.25)
      (net 1 "GND") (pintype "passive"))
  )
	(footprint "kria-k26-devboard-footprints:C_0402_1005Metric" (layer "B.Cu")
    (at 148.5 121.66 90)
    (descr "Capacitor SMD 0402")
    (tags "capacitor SMD 0402")
    (property "Author" "Antmicro")
    (property "Dielectric" "X5R")
    (property "License" "Apache-2.0")
    (property "MPN" "GRM155R61H104KE14D")
    (property "Manufacturer" "Murata")
    (property "Sheetfile" "debug.kicad_sch")
    (property "Sheetname" "Debug and JTAG")
    (property "Val" "100n")
    (property "Voltage" "50V")
    (property "ki_description" " ")
    (attr smd)
    (fp_text reference "C142" (at 1.26 4.35 270) (layer "B.SilkS")
        (effects (font (size 0.7 0.7) (thickness 0.15)) (justify left bottom mirror))
    )
    (fp_text value "C_100n_0402" (at 0 -1.4 270) (layer "B.Fab") hide
        (effects (font (size 0.7 0.7) (thickness 0.15)) (justify left bottom mirror))
    )
    (fp_text user "${REFERENCE}" (at -0.932 -3.168 270) (layer "B.Fab") hide
        (effects (font (size 0.7 0.7) (thickness 0.15)) (justify left bottom mirror))
    )
    (fp_text user "Author: Antmicro" (at -0.932 -4.17 270) (layer "B.Fab") hide
        (effects (font (size 0.7 0.7) (thickness 0.15)) (justify left bottom mirror))
    )
    (fp_text user "License: Apache-2.0" (at -0.932 -5.17 270) (layer "B.Fab") hide
        (effects (font (size 0.7 0.7) (thickness 0.15)) (justify left bottom mirror))
    )
    (fp_rect (start -0.94 0.47) (end 0.94 -0.47)
      (stroke (width 0.05) (type solid)) (fill none) (layer "B.CrtYd"))
    (fp_rect (start -0.499 0.249) (end 0.499 -0.249)
      (stroke (width 0.15) (type solid)) (fill none) (layer "B.Fab"))
    (pad "1" smd roundrect (at -0.484 0 90) (size 0.59 0.64) (layers "B.Cu" "B.Paste" "B.Mask") (roundrect_rratio 0.25)
      (net 138 "/Debug and JTAG/USB_3V3") (pintype "passive"))
    (pad "2" smd roundrect (at 0.484 0 90) (size 0.59 0.64) (layers "B.Cu" "B.Paste" "B.Mask") (roundrect_rratio 0.25)
      (net 1 "GND") (pintype "passive"))
  )
	(footprint "kria-k26-devboard-footprints:R_0402_1005Metric" (layer "B.Cu")
    (at 139.95 92.6)
    (descr "Resistor SMD 0402")
    (tags "resistor SMD 0402")
    (property "Author" "Antmicro")
    (property "License" "Apache-2.0")
    (property "MPN" "CR0402-FX-5100GLF")
    (property "Manufacturer" "Bourns")
    (property "Sheetfile" "dc-dc-conventers.kicad_sch")
    (property "Sheetname" "DC/DC conventers")
    (property "Tolerance" "1%")
    (property "Val" "510R")
    (property "ki_description" "510R resistor in 0402 package with 1% tolerance")
    (attr smd)
    (fp_text reference "R141" (at 3.68 0.38 180) (layer "B.SilkS")
        (effects (font (size 0.7 0.7) (thickness 0.15)) (justify left bottom mirror))
    )
    (fp_text value "R_510R_0402" (at 0 -1.4 180) (layer "B.Fab") hide
        (effects (font (size 0.7 0.7) (thickness 0.15)) (justify left bottom mirror))
    )
    (fp_text user "${REFERENCE}" (at -0.95 -3.168 180) (layer "B.Fab") hide
        (effects (font (size 0.7 0.7) (thickness 0.15)) (justify left bottom mirror))
    )
    (fp_text user "Author: Antmicro" (at -0.95 -4.169 180) (layer "B.Fab") hide
        (effects (font (size 0.7 0.7) (thickness 0.15)) (justify left bottom mirror))
    )
    (fp_text user "License: Apache-2.0" (at -0.95 -5.169 180) (layer "B.Fab") hide
        (effects (font (size 0.7 0.7) (thickness 0.15)) (justify left bottom mirror))
    )
    (fp_rect (start -0.93 0.47) (end 0.93 -0.47)
      (stroke (width 0.05) (type solid)) (fill none) (layer "B.CrtYd"))
    (fp_rect (start -0.5 0.25) (end 0.5 -0.25)
      (stroke (width 0.15) (type solid)) (fill none) (layer "B.Fab"))
    (pad "1" smd roundrect (at -0.485 0) (size 0.59 0.64) (layers "B.Cu" "B.Paste" "B.Mask") (roundrect_rratio 0.25)
      (net 190 "Net-(D18-Pad1)") (pintype "passive"))
    (pad "2" smd roundrect (at 0.485 0) (size 0.59 0.64) (layers "B.Cu" "B.Paste" "B.Mask") (roundrect_rratio 0.25)
      (net 766 "/Power Supply/DC/DC conventers/PS_2V5_OUT") (pintype "passive"))
  )
)
